(kicad_pcb
	(version 20260206)
	(generator "pcbnew")
	(generator_version "10.0")
	(general
		(thickness 1.6)
		(legacy_teardrops no)
	)
	(paper "A4")
	(title_block
		(title "03242023_DA0F0TMBIJ0_F0T_Motherboard_J_brd_V01_OCP.brd")
		(comment 1 "Grand Teton / footprints 791-795 of 6105")
	)
	(layers
		(0 "F.Cu" signal "TOP")
		(4 "In1.Cu" signal "GND")
		(6 "In2.Cu" signal "IN1")
		(8 "In3.Cu" signal "GND1")
		(10 "In4.Cu" signal "IN2")
		(12 "In5.Cu" signal "GND2")
		(14 "In6.Cu" signal "IN3")
		(16 "In7.Cu" signal "GND3")
		(18 "In8.Cu" signal "VCC")
		(20 "In9.Cu" signal "VCC1")
		(22 "In10.Cu" signal "GND4")
		(24 "In11.Cu" signal "IN4")
		(26 "In12.Cu" signal "GND5")
		(28 "In13.Cu" signal "IN5")
		(30 "In14.Cu" signal "GND6")
		(32 "In15.Cu" signal "IN6")
		(34 "In16.Cu" signal "GND7")
		(2 "B.Cu" signal "BOTTOM")
		(9 "F.Adhes" user "F.Adhesive")
		(11 "B.Adhes" user "B.Adhesive")
		(13 "F.Paste" user "Package Geometry/Pastemask Top")
		(15 "B.Paste" user "Package Geometry/Pastemask Bottom")
		(5 "F.SilkS" user "Ref Des/Silkscreen Top")
		(7 "B.SilkS" user "Ref Des/Silkscreen Bottom")
		(1 "F.Mask" user "Board Geometry/Soldermask Top")
		(3 "B.Mask" user "Board Geometry/Soldermask Bottom")
		(17 "Dwgs.User" user "User.Drawings")
		(19 "Cmts.User" user "User.Comments")
		(21 "Eco1.User" user "User.Eco1")
		(23 "Eco2.User" user "User.Eco2")
		(25 "Edge.Cuts" user "Board Geometry/Outline")
		(27 "Margin" user)
		(31 "F.CrtYd" user "Package Geometry/Place Bound Top")
		(29 "B.CrtYd" user "Package Geometry/Place Bound Bottom")
		(35 "F.Fab" user "Ref Des/Assembly Top")
		(33 "B.Fab" user "Ref Des/Assembly Bottom")
	)
	(footprint ""
		(layer "F.Cu")
		(at 368.7572 -71.42226)
		(property "Reference" "D142"
			(at -5.7912 -0.94107 0)
			(unlocked yes)
			(layer "F.SilkS")
			(effects
				(font
					(size 0.7874 0.5842)
					(thickness 0.1524)
				)
				(justify left)
			)
		)
		(property "Value" ""
			(at 0 0 0)
			(layer "F.Fab")
			(effects
				(font
					(size 1.27 1.27)
				)
			)
		)
		(duplicate_pad_numbers_are_jumpers no)
		(fp_line
			(start -0.90678 0.4826)
			(end -0.90678 -0.4699)
			(stroke
				(width 0.1524)
				(type default)
			)
			(layer "F.SilkS")
		)
		(fp_line
			(start -0.89408 -0.4826)
			(end 0.90678 -0.4826)
			(stroke
				(width 0.1524)
				(type default)
			)
			(layer "F.SilkS")
		)
		(fp_line
			(start -0.79248 -0.4826)
			(end 1.03378 -0.4826)
			(stroke
				(width 0.1524)
				(type default)
			)
			(layer "F.SilkS")
		)
		(fp_line
			(start -0.64008 -0.4826)
			(end 1.16078 -0.4826)
			(stroke
				(width 0.1524)
				(type default)
			)
			(layer "F.SilkS")
		)
		(fp_line
			(start 0.90678 -0.4826)
			(end 0.90678 0.4826)
			(stroke
				(width 0.1524)
				(type default)
			)
			(layer "F.SilkS")
		)
		(fp_line
			(start 0.90678 0.4826)
			(end -0.90678 0.4826)
			(stroke
				(width 0.1524)
				(type default)
			)
			(layer "F.SilkS")
		)
		(fp_line
			(start 1.03378 -0.4826)
			(end 1.03378 0.4826)
			(stroke
				(width 0.1524)
				(type default)
			)
			(layer "F.SilkS")
		)
		(fp_line
			(start 1.03378 0.4826)
			(end -0.79248 0.4826)
			(stroke
				(width 0.1524)
				(type default)
			)
			(layer "F.SilkS")
		)
		(fp_line
			(start 1.16078 -0.4826)
			(end 1.16078 0.4826)
			(stroke
				(width 0.1524)
				(type default)
			)
			(layer "F.SilkS")
		)
		(fp_line
			(start 1.16078 0.4826)
			(end -0.64008 0.4826)
			(stroke
				(width 0.1524)
				(type default)
			)
			(layer "F.SilkS")
		)
		(fp_line
			(start -0.499872 -0.249936)
			(end 0.499872 -0.249936)
			(stroke
				(width 0.1)
				(type default)
			)
			(layer "F.Fab")
		)
		(fp_line
			(start -0.499872 0.249936)
			(end -0.499872 -0.249936)
			(stroke
				(width 0.1)
				(type default)
			)
			(layer "F.Fab")
		)
		(fp_line
			(start 0.499872 -0.249936)
			(end 0.499872 0.249936)
			(stroke
				(width 0.1)
				(type default)
			)
			(layer "F.Fab")
		)
		(fp_line
			(start 0.499872 0.249936)
			(end -0.499872 0.249936)
			(stroke
				(width 0.1)
				(type default)
			)
			(layer "F.Fab")
		)
		(pad "A" smd rect
			(at -0.47498 0)
			(size 0.6096 0.7112)
			(layers "F.Cu" "F.Mask" "F.Paste")
			(net "LED_P12V_AUX_R1")
		)
		(pad "C" smd rect
			(at 0.47498 0)
			(size 0.6096 0.7112)
			(layers "F.Cu" "F.Mask" "F.Paste")
			(net "GND")
		)
	)
	(footprint ""
		(layer "F.Cu")
		(at 420.4716 -177.724562 180)
		(property "Reference" "PC194"
			(at 0 0 180)
			(layer "F.SilkS")
			(hide yes)
			(effects
				(font
					(size 1.27 1.27)
				)
			)
		)
		(property "Value" ""
			(at 0 0 180)
			(layer "F.Fab")
			(effects
				(font
					(size 1.27 1.27)
				)
			)
		)
		(duplicate_pad_numbers_are_jumpers no)
		(fp_line
			(start 0.7874 0.4064)
			(end -0.7874 0.4064)
			(stroke
				(width 0.1524)
				(type default)
			)
			(layer "F.SilkS")
		)
		(fp_line
			(start 0.7874 -0.4064)
			(end 0.7874 0.4064)
			(stroke
				(width 0.1524)
				(type default)
			)
			(layer "F.SilkS")
		)
		(fp_line
			(start -0.7874 0.4064)
			(end -0.7874 -0.4064)
			(stroke
				(width 0.1524)
				(type default)
			)
			(layer "F.SilkS")
		)
		(fp_line
			(start -0.7874 -0.4064)
			(end 0.7874 -0.4064)
			(stroke
				(width 0.1524)
				(type default)
			)
			(layer "F.SilkS")
		)
		(fp_line
			(start 0.67945 0.3048)
			(end 0.120396 0.3048)
			(stroke
				(width 0.1)
				(type default)
			)
			(layer "F.Fab")
		)
		(fp_line
			(start 0.67945 -0.3048)
			(end 0.67945 0.3048)
			(stroke
				(width 0.1)
				(type default)
			)
			(layer "F.Fab")
		)
		(fp_line
			(start 0.12065 -0.2794)
			(end 0.12065 -0.3048)
			(stroke
				(width 0.1)
				(type default)
			)
			(layer "F.Fab")
		)
		(fp_line
			(start 0.12065 -0.3048)
			(end 0.67945 -0.3048)
			(stroke
				(width 0.1)
				(type default)
			)
			(layer "F.Fab")
		)
		(fp_line
			(start 0.120396 0.3048)
			(end 0.120396 0.2794)
			(stroke
				(width 0.1)
				(type default)
			)
			(layer "F.Fab")
		)
		(fp_line
			(start 0.120396 0.2794)
			(end -0.12065 0.2794)
			(stroke
				(width 0.1)
				(type default)
			)
			(layer "F.Fab")
		)
		(fp_line
			(start -0.12065 0.3048)
			(end -0.67945 0.3048)
			(stroke
				(width 0.1)
				(type default)
			)
			(layer "F.Fab")
		)
		(fp_line
			(start -0.12065 0.2794)
			(end -0.12065 0.3048)
			(stroke
				(width 0.1)
				(type default)
			)
			(layer "F.Fab")
		)
		(fp_line
			(start -0.12065 -0.2794)
			(end 0.12065 -0.2794)
			(stroke
				(width 0.1)
				(type default)
			)
			(layer "F.Fab")
		)
		(fp_line
			(start -0.12065 -0.305054)
			(end -0.12065 -0.2794)
			(stroke
				(width 0.1)
				(type default)
			)
			(layer "F.Fab")
		)
		(fp_line
			(start -0.67945 0.3048)
			(end -0.67945 -0.305054)
			(stroke
				(width 0.1)
				(type default)
			)
			(layer "F.Fab")
		)
		(fp_line
			(start -0.67945 -0.305054)
			(end -0.12065 -0.305054)
			(stroke
				(width 0.1)
				(type default)
			)
			(layer "F.Fab")
		)
		(pad "1" smd circle
			(at -0.40005 0 180)
			(size 0 0)
			(layers "F.Cu" "F.Mask" "F.Paste")
			(net "SW_PVCCINFAON_CPU0_BOOT2_R")
		)
		(pad "2" smd circle
			(at 0.40005 0 180)
			(size 0 0)
			(layers "F.Cu" "F.Mask" "F.Paste")
			(net "SW_PVCCINFAON_CPU0_BOOTR2")
		)
	)
	(footprint ""
		(layer "F.Cu")
		(at 224.074482 -57.412382 90)
		(property "Reference" "R3767"
			(at 0 0 90)
			(layer "F.SilkS")
			(hide yes)
			(effects
				(font
					(size 1.27 1.27)
				)
			)
		)
		(property "Value" ""
			(at 0 0 90)
			(layer "F.Fab")
			(effects
				(font
					(size 1.27 1.27)
				)
			)
		)
		(duplicate_pad_numbers_are_jumpers no)
		(fp_line
			(start 4.0386 -1.7526)
			(end 4.0386 1.7526)
			(stroke
				(width 0.1524)
				(type default)
			)
			(layer "F.SilkS")
		)
		(fp_line
			(start -4.0386 -1.7526)
			(end 4.0386 -1.7526)
			(stroke
				(width 0.1524)
				(type default)
			)
			(layer "F.SilkS")
		)
		(fp_line
			(start 4.0386 1.7526)
			(end -4.0386 1.7526)
			(stroke
				(width 0.1524)
				(type default)
			)
			(layer "F.SilkS")
		)
		(fp_line
			(start -4.0386 1.7526)
			(end -4.0386 -1.7526)
			(stroke
				(width 0.1524)
				(type default)
			)
			(layer "F.SilkS")
		)
		(fp_line
			(start 4.0386 -1.7526)
			(end 4.0386 1.7526)
			(stroke
				(width 0.1)
				(type default)
			)
			(layer "F.Fab")
		)
		(fp_line
			(start -4.0386 -1.7526)
			(end 4.0386 -1.7526)
			(stroke
				(width 0.1)
				(type default)
			)
			(layer "F.Fab")
		)
		(fp_line
			(start 4.0386 1.7526)
			(end -4.0386 1.7526)
			(stroke
				(width 0.1)
				(type default)
			)
			(layer "F.Fab")
		)
		(fp_line
			(start -4.0386 1.7526)
			(end -4.0386 -1.7526)
			(stroke
				(width 0.1)
				(type default)
			)
			(layer "F.Fab")
		)
		(pad "1" smd rect
			(at -3.1115 0 90)
			(size 1.524 3.2004)
			(layers "F.Cu" "F.Mask" "F.Paste")
			(net "P3V3_E1S_0")
		)
		(pad "2" smd rect
			(at 3.1115 0 90)
			(size 1.524 3.2004)
			(layers "F.Cu" "F.Mask" "F.Paste")
			(net "P3V3_E1S_0_R")
		)
	)
	(footprint ""
		(layer "F.Cu")
		(at 111.332772 -129.472182)
		(property "Reference" "R1089"
			(at 0 0 0)
			(layer "F.SilkS")
			(hide yes)
			(effects
				(font
					(size 1.27 1.27)
				)
			)
		)
		(property "Value" ""
			(at 0 0 0)
			(layer "F.Fab")
			(effects
				(font
					(size 1.27 1.27)
				)
			)
		)
		(duplicate_pad_numbers_are_jumpers no)
		(fp_line
			(start -0.7874 -0.4064)
			(end 0.7874 -0.4064)
			(stroke
				(width 0.1524)
				(type default)
			)
			(layer "F.SilkS")
		)
		(fp_line
			(start -0.7874 0.4064)
			(end -0.7874 -0.4064)
			(stroke
				(width 0.1524)
				(type default)
			)
			(layer "F.SilkS")
		)
		(fp_line
			(start 0.7874 -0.4064)
			(end 0.7874 0.4064)
			(stroke
				(width 0.1524)
				(type default)
			)
			(layer "F.SilkS")
		)
		(fp_line
			(start 0.7874 0.4064)
			(end -0.7874 0.4064)
			(stroke
				(width 0.1524)
				(type default)
			)
			(layer "F.SilkS")
		)
		(fp_line
			(start -0.67945 -0.305054)
			(end -0.12065 -0.305054)
			(stroke
				(width 0.1)
				(type default)
			)
			(layer "F.Fab")
		)
		(fp_line
			(start -0.67945 0.3048)
			(end -0.67945 -0.305054)
			(stroke
				(width 0.1)
				(type default)
			)
			(layer "F.Fab")
		)
		(fp_line
			(start -0.12065 -0.305054)
			(end -0.12065 -0.2794)
			(stroke
				(width 0.1)
				(type default)
			)
			(layer "F.Fab")
		)
		(fp_line
			(start -0.12065 -0.2794)
			(end 0.12065 -0.2794)
			(stroke
				(width 0.1)
				(type default)
			)
			(layer "F.Fab")
		)
		(fp_line
			(start -0.12065 0.2794)
			(end -0.12065 0.3048)
			(stroke
				(width 0.1)
				(type default)
			)
			(layer "F.Fab")
		)
		(fp_line
			(start -0.12065 0.3048)
			(end -0.67945 0.3048)
			(stroke
				(width 0.1)
				(type default)
			)
			(layer "F.Fab")
		)
		(fp_line
			(start 0.120396 0.2794)
			(end -0.12065 0.2794)
			(stroke
				(width 0.1)
				(type default)
			)
			(layer "F.Fab")
		)
		(fp_line
			(start 0.120396 0.3048)
			(end 0.120396 0.2794)
			(stroke
				(width 0.1)
				(type default)
			)
			(layer "F.Fab")
		)
		(fp_line
			(start 0.12065 -0.3048)
			(end 0.67945 -0.3048)
			(stroke
				(width 0.1)
				(type default)
			)
			(layer "F.Fab")
		)
		(fp_line
			(start 0.12065 -0.2794)
			(end 0.12065 -0.3048)
			(stroke
				(width 0.1)
				(type default)
			)
			(layer "F.Fab")
		)
		(fp_line
			(start 0.67945 -0.3048)
			(end 0.67945 0.3048)
			(stroke
				(width 0.1)
				(type default)
			)
			(layer "F.Fab")
		)
		(fp_line
			(start 0.67945 0.3048)
			(end 0.120396 0.3048)
			(stroke
				(width 0.1)
				(type default)
			)
			(layer "F.Fab")
		)
		(pad "1" smd circle
			(at -0.40005 0)
			(size 0 0)
			(layers "F.Cu" "F.Mask" "F.Paste")
			(net "P3V3_AUX")
		)
		(pad "2" smd circle
			(at 0.40005 0)
			(size 0 0)
			(layers "F.Cu" "F.Mask" "F.Paste")
			(net "SMB_SENSOR_M2_P0_3V3AUX_SCL")
		)
	)
	(footprint ""
		(layer "F.Cu")
		(at 152.70988 -122.519948)
		(property "Reference" "R2344"
			(at 0 0 0)
			(layer "F.SilkS")
			(hide yes)
			(effects
				(font
					(size 1.27 1.27)
				)
			)
		)
		(property "Value" ""
			(at 0 0 0)
			(layer "F.Fab")
			(effects
				(font
					(size 1.27 1.27)
				)
			)
		)
		(duplicate_pad_numbers_are_jumpers no)
		(fp_line
			(start -0.7874 -0.4064)
			(end 0.7874 -0.4064)
			(stroke
				(width 0.1524)
				(type default)
			)
			(layer "F.SilkS")
		)
		(fp_line
			(start -0.7874 0.4064)
			(end -0.7874 -0.4064)
			(stroke
				(width 0.1524)
				(type default)
			)
			(layer "F.SilkS")
		)
		(fp_line
			(start 0.7874 -0.4064)
			(end 0.7874 0.4064)
			(stroke
				(width 0.1524)
				(type default)
			)
			(layer "F.SilkS")
		)
		(fp_line
			(start 0.7874 0.4064)
			(end -0.7874 0.4064)
			(stroke
				(width 0.1524)
				(type default)
			)
			(layer "F.SilkS")
		)
		(fp_line
			(start -0.67945 -0.305054)
			(end -0.12065 -0.305054)
			(stroke
				(width 0.1)
				(type default)
			)
			(layer "F.Fab")
		)
		(fp_line
			(start -0.67945 0.3048)
			(end -0.67945 -0.305054)
			(stroke
				(width 0.1)
				(type default)
			)
			(layer "F.Fab")
		)
		(fp_line
			(start -0.12065 -0.305054)
			(end -0.12065 -0.2794)
			(stroke
				(width 0.1)
				(type default)
			)
			(layer "F.Fab")
		)
		(fp_line
			(start -0.12065 -0.2794)
			(end 0.12065 -0.2794)
			(stroke
				(width 0.1)
				(type default)
			)
			(layer "F.Fab")
		)
		(fp_line
			(start -0.12065 0.2794)
			(end -0.12065 0.3048)
			(stroke
				(width 0.1)
				(type default)
			)
			(layer "F.Fab")
		)
		(fp_line
			(start -0.12065 0.3048)
			(end -0.67945 0.3048)
			(stroke
				(width 0.1)
				(type default)
			)
			(layer "F.Fab")
		)
		(fp_line
			(start 0.120396 0.2794)
			(end -0.12065 0.2794)
			(stroke
				(width 0.1)
				(type default)
			)
			(layer "F.Fab")
		)
		(fp_line
			(start 0.120396 0.3048)
			(end 0.120396 0.2794)
			(stroke
				(width 0.1)
				(type default)
			)
			(layer "F.Fab")
		)
		(fp_line
			(start 0.12065 -0.3048)
			(end 0.67945 -0.3048)
			(stroke
				(width 0.1)
				(type default)
			)
			(layer "F.Fab")
		)
		(fp_line
			(start 0.12065 -0.2794)
			(end 0.12065 -0.3048)
			(stroke
				(width 0.1)
				(type default)
			)
			(layer "F.Fab")
		)
		(fp_line
			(start 0.67945 -0.3048)
			(end 0.67945 0.3048)
			(stroke
				(width 0.1)
				(type default)
			)
			(layer "F.Fab")
		)
		(fp_line
			(start 0.67945 0.3048)
			(end 0.120396 0.3048)
			(stroke
				(width 0.1)
				(type default)
			)
			(layer "F.Fab")
		)
		(pad "1" smd circle
			(at -0.40005 0)
			(size 0 0)
			(layers "F.Cu" "F.Mask" "F.Paste")
			(net "P3V3_AUX")
		)
		(pad "2" smd circle
			(at 0.40005 0)
			(size 0 0)
			(layers "F.Cu" "F.Mask" "F.Paste")
			(net "PWRGD_P5V_AUX_R1")
		)
	)
)
